(kicad_pcb
	(version 20260206)
	(generator "pcbnew")
	(generator_version "10.0")
	(general
		(thickness 1.6)
		(legacy_teardrops no)
	)
	(paper "A4")
	(title_block
		(title "01162023_DA0F0TEBIF0_F0T_Expander_BD_F_brd_V02_OCP.brd")
		(comment 1 "Grand Teton / footprints 5650-5654 of 9728")
	)
	(layers
		(0 "F.Cu" signal "TOP")
		(4 "In1.Cu" signal "GND")
		(6 "In2.Cu" signal "VCC")
		(8 "In3.Cu" signal "VCC1")
		(10 "In4.Cu" signal "GND1")
		(12 "In5.Cu" signal "IN1")
		(14 "In6.Cu" signal "GND2")
		(16 "In7.Cu" signal "IN2")
		(18 "In8.Cu" signal "GND3")
		(20 "In9.Cu" signal "IN3")
		(22 "In10.Cu" signal "GND4")
		(24 "In11.Cu" signal "IN4")
		(26 "In12.Cu" signal "GND5")
		(28 "In13.Cu" signal "IN5")
		(30 "In14.Cu" signal "GND6")
		(32 "In15.Cu" signal "IN6")
		(34 "In16.Cu" signal "GND7")
		(2 "B.Cu" signal "BOTTOM")
		(9 "F.Adhes" user "F.Adhesive")
		(11 "B.Adhes" user "B.Adhesive")
		(13 "F.Paste" user "Package Geometry/Pastemask Top")
		(15 "B.Paste" user "Package Geometry/Pastemask Bottom")
		(5 "F.SilkS" user "Ref Des/Silkscreen Top")
		(7 "B.SilkS" user "Ref Des/Silkscreen Bottom")
		(1 "F.Mask" user "Board Geometry/Soldermask Top")
		(3 "B.Mask" user "Board Geometry/Soldermask Bottom")
		(17 "Dwgs.User" user "User.Drawings")
		(19 "Cmts.User" user "User.Comments")
		(21 "Eco1.User" user "User.Eco1")
		(23 "Eco2.User" user "User.Eco2")
		(25 "Edge.Cuts" user "Board Geometry/Outline")
		(27 "Margin" user)
		(31 "F.CrtYd" user "Package Geometry/Place Bound Top")
		(29 "B.CrtYd" user "Package Geometry/Place Bound Bottom")
		(35 "F.Fab" user "Ref Des/Assembly Top")
		(33 "B.Fab" user "Ref Des/Assembly Bottom")
	)
	(footprint ""
		(layer "F.Cu")
		(at 101.17455 -240.928144)
		(property "Reference" "C829"
			(at 0 0 0)
			(layer "F.SilkS")
			(hide yes)
			(effects
				(font
					(size 1.27 1.27)
				)
			)
		)
		(property "Value" ""
			(at 0 0 0)
			(layer "F.Fab")
			(effects
				(font
					(size 1.27 1.27)
				)
			)
		)
		(duplicate_pad_numbers_are_jumpers no)
		(fp_line
			(start -0.7874 -0.4064)
			(end 0.7874 -0.4064)
			(stroke
				(width 0.1524)
				(type default)
			)
			(layer "F.SilkS")
		)
		(fp_line
			(start -0.7874 0.4064)
			(end -0.7874 -0.4064)
			(stroke
				(width 0.1524)
				(type default)
			)
			(layer "F.SilkS")
		)
		(fp_line
			(start 0.7874 -0.4064)
			(end 0.7874 0.4064)
			(stroke
				(width 0.1524)
				(type default)
			)
			(layer "F.SilkS")
		)
		(fp_line
			(start 0.7874 0.4064)
			(end -0.7874 0.4064)
			(stroke
				(width 0.1524)
				(type default)
			)
			(layer "F.SilkS")
		)
		(fp_line
			(start -0.67945 -0.305054)
			(end -0.12065 -0.305054)
			(stroke
				(width 0.1)
				(type default)
			)
			(layer "F.Fab")
		)
		(fp_line
			(start -0.67945 0.3048)
			(end -0.67945 -0.305054)
			(stroke
				(width 0.1)
				(type default)
			)
			(layer "F.Fab")
		)
		(fp_line
			(start -0.12065 -0.305054)
			(end -0.12065 -0.2794)
			(stroke
				(width 0.1)
				(type default)
			)
			(layer "F.Fab")
		)
		(fp_line
			(start -0.12065 -0.2794)
			(end 0.12065 -0.2794)
			(stroke
				(width 0.1)
				(type default)
			)
			(layer "F.Fab")
		)
		(fp_line
			(start -0.12065 0.2794)
			(end -0.12065 0.3048)
			(stroke
				(width 0.1)
				(type default)
			)
			(layer "F.Fab")
		)
		(fp_line
			(start -0.12065 0.3048)
			(end -0.67945 0.3048)
			(stroke
				(width 0.1)
				(type default)
			)
			(layer "F.Fab")
		)
		(fp_line
			(start 0.120396 0.2794)
			(end -0.12065 0.2794)
			(stroke
				(width 0.1)
				(type default)
			)
			(layer "F.Fab")
		)
		(fp_line
			(start 0.120396 0.3048)
			(end 0.120396 0.2794)
			(stroke
				(width 0.1)
				(type default)
			)
			(layer "F.Fab")
		)
		(fp_line
			(start 0.12065 -0.3048)
			(end 0.67945 -0.3048)
			(stroke
				(width 0.1)
				(type default)
			)
			(layer "F.Fab")
		)
		(fp_line
			(start 0.12065 -0.2794)
			(end 0.12065 -0.3048)
			(stroke
				(width 0.1)
				(type default)
			)
			(layer "F.Fab")
		)
		(fp_line
			(start 0.67945 -0.3048)
			(end 0.67945 0.3048)
			(stroke
				(width 0.1)
				(type default)
			)
			(layer "F.Fab")
		)
		(fp_line
			(start 0.67945 0.3048)
			(end 0.120396 0.3048)
			(stroke
				(width 0.1)
				(type default)
			)
			(layer "F.Fab")
		)
		(pad "1" smd circle
			(at -0.40005 0)
			(size 0 0)
			(layers "F.Cu" "F.Mask" "F.Paste")
			(net "P3V3_AUX")
		)
		(pad "2" smd circle
			(at 0.40005 0)
			(size 0 0)
			(layers "F.Cu" "F.Mask" "F.Paste")
			(net "GND")
		)
	)
	(footprint ""
		(layer "F.Cu")
		(at 58.0644 -140.6398 180)
		(property "Reference" "R38"
			(at 0 0 180)
			(layer "F.SilkS")
			(hide yes)
			(effects
				(font
					(size 1.27 1.27)
				)
			)
		)
		(property "Value" ""
			(at 0 0 180)
			(layer "F.Fab")
			(effects
				(font
					(size 1.27 1.27)
				)
			)
		)
		(duplicate_pad_numbers_are_jumpers no)
		(fp_line
			(start 0.7874 0.4064)
			(end -0.7874 0.4064)
			(stroke
				(width 0.1524)
				(type default)
			)
			(layer "F.SilkS")
		)
		(fp_line
			(start 0.7874 -0.4064)
			(end 0.7874 0.4064)
			(stroke
				(width 0.1524)
				(type default)
			)
			(layer "F.SilkS")
		)
		(fp_line
			(start -0.7874 0.4064)
			(end -0.7874 -0.4064)
			(stroke
				(width 0.1524)
				(type default)
			)
			(layer "F.SilkS")
		)
		(fp_line
			(start -0.7874 -0.4064)
			(end 0.7874 -0.4064)
			(stroke
				(width 0.1524)
				(type default)
			)
			(layer "F.SilkS")
		)
		(fp_line
			(start 0.67945 0.3048)
			(end 0.120396 0.3048)
			(stroke
				(width 0.1)
				(type default)
			)
			(layer "F.Fab")
		)
		(fp_line
			(start 0.67945 -0.3048)
			(end 0.67945 0.3048)
			(stroke
				(width 0.1)
				(type default)
			)
			(layer "F.Fab")
		)
		(fp_line
			(start 0.12065 -0.2794)
			(end 0.12065 -0.3048)
			(stroke
				(width 0.1)
				(type default)
			)
			(layer "F.Fab")
		)
		(fp_line
			(start 0.12065 -0.3048)
			(end 0.67945 -0.3048)
			(stroke
				(width 0.1)
				(type default)
			)
			(layer "F.Fab")
		)
		(fp_line
			(start 0.120396 0.3048)
			(end 0.120396 0.2794)
			(stroke
				(width 0.1)
				(type default)
			)
			(layer "F.Fab")
		)
		(fp_line
			(start 0.120396 0.2794)
			(end -0.12065 0.2794)
			(stroke
				(width 0.1)
				(type default)
			)
			(layer "F.Fab")
		)
		(fp_line
			(start -0.12065 0.3048)
			(end -0.67945 0.3048)
			(stroke
				(width 0.1)
				(type default)
			)
			(layer "F.Fab")
		)
		(fp_line
			(start -0.12065 0.2794)
			(end -0.12065 0.3048)
			(stroke
				(width 0.1)
				(type default)
			)
			(layer "F.Fab")
		)
		(fp_line
			(start -0.12065 -0.2794)
			(end 0.12065 -0.2794)
			(stroke
				(width 0.1)
				(type default)
			)
			(layer "F.Fab")
		)
		(fp_line
			(start -0.12065 -0.305054)
			(end -0.12065 -0.2794)
			(stroke
				(width 0.1)
				(type default)
			)
			(layer "F.Fab")
		)
		(fp_line
			(start -0.67945 0.3048)
			(end -0.67945 -0.305054)
			(stroke
				(width 0.1)
				(type default)
			)
			(layer "F.Fab")
		)
		(fp_line
			(start -0.67945 -0.305054)
			(end -0.12065 -0.305054)
			(stroke
				(width 0.1)
				(type default)
			)
			(layer "F.Fab")
		)
		(pad "1" smd circle
			(at -0.40005 0 180)
			(size 0 0)
			(layers "F.Cu" "F.Mask" "F.Paste")
			(net "RST_SMB_NIC0_MUX_ISO_N")
		)
		(pad "2" smd circle
			(at 0.40005 0 180)
			(size 0 0)
			(layers "F.Cu" "F.Mask" "F.Paste")
			(net "GND")
		)
	)
	(footprint ""
		(layer "F.Cu")
		(at 187.838588 -44.341542 90)
		(property "Reference" "C317"
			(at 0 0 90)
			(layer "F.SilkS")
			(hide yes)
			(effects
				(font
					(size 1.27 1.27)
				)
			)
		)
		(property "Value" ""
			(at 0 0 90)
			(layer "F.Fab")
			(effects
				(font
					(size 1.27 1.27)
				)
			)
		)
		(duplicate_pad_numbers_are_jumpers no)
		(fp_line
			(start 0.7874 -0.4064)
			(end 0.7874 0.4064)
			(stroke
				(width 0.1524)
				(type default)
			)
			(layer "F.SilkS")
		)
		(fp_line
			(start -0.7874 -0.4064)
			(end 0.7874 -0.4064)
			(stroke
				(width 0.1524)
				(type default)
			)
			(layer "F.SilkS")
		)
		(fp_line
			(start 0.7874 0.4064)
			(end -0.7874 0.4064)
			(stroke
				(width 0.1524)
				(type default)
			)
			(layer "F.SilkS")
		)
		(fp_line
			(start -0.7874 0.4064)
			(end -0.7874 -0.4064)
			(stroke
				(width 0.1524)
				(type default)
			)
			(layer "F.SilkS")
		)
		(fp_line
			(start -0.12065 -0.305054)
			(end -0.12065 -0.2794)
			(stroke
				(width 0.1)
				(type default)
			)
			(layer "F.Fab")
		)
		(fp_line
			(start -0.67945 -0.305054)
			(end -0.12065 -0.305054)
			(stroke
				(width 0.1)
				(type default)
			)
			(layer "F.Fab")
		)
		(fp_line
			(start 0.67945 -0.3048)
			(end 0.67945 0.3048)
			(stroke
				(width 0.1)
				(type default)
			)
			(layer "F.Fab")
		)
		(fp_line
			(start 0.12065 -0.3048)
			(end 0.67945 -0.3048)
			(stroke
				(width 0.1)
				(type default)
			)
			(layer "F.Fab")
		)
		(fp_line
			(start 0.12065 -0.2794)
			(end 0.12065 -0.3048)
			(stroke
				(width 0.1)
				(type default)
			)
			(layer "F.Fab")
		)
		(fp_line
			(start -0.12065 -0.2794)
			(end 0.12065 -0.2794)
			(stroke
				(width 0.1)
				(type default)
			)
			(layer "F.Fab")
		)
		(fp_line
			(start 0.120396 0.2794)
			(end -0.12065 0.2794)
			(stroke
				(width 0.1)
				(type default)
			)
			(layer "F.Fab")
		)
		(fp_line
			(start -0.12065 0.2794)
			(end -0.12065 0.3048)
			(stroke
				(width 0.1)
				(type default)
			)
			(layer "F.Fab")
		)
		(fp_line
			(start 0.67945 0.3048)
			(end 0.120396 0.3048)
			(stroke
				(width 0.1)
				(type default)
			)
			(layer "F.Fab")
		)
		(fp_line
			(start 0.120396 0.3048)
			(end 0.120396 0.2794)
			(stroke
				(width 0.1)
				(type default)
			)
			(layer "F.Fab")
		)
		(fp_line
			(start -0.12065 0.3048)
			(end -0.67945 0.3048)
			(stroke
				(width 0.1)
				(type default)
			)
			(layer "F.Fab")
		)
		(fp_line
			(start -0.67945 0.3048)
			(end -0.67945 -0.305054)
			(stroke
				(width 0.1)
				(type default)
			)
			(layer "F.Fab")
		)
		(pad "1" smd circle
			(at -0.40005 0 90)
			(size 0 0)
			(layers "F.Cu" "F.Mask" "F.Paste")
			(net "P12V_SSD6_VIN_P")
		)
		(pad "2" smd circle
			(at 0.40005 0 90)
			(size 0 0)
			(layers "F.Cu" "F.Mask" "F.Paste")
			(net "P12V_SSD6_VIN_N")
		)
	)
	(footprint ""
		(layer "F.Cu")
		(at 94.494096 -116.410486)
		(property "Reference" "PR6917"
			(at 0 0 0)
			(layer "F.SilkS")
			(hide yes)
			(effects
				(font
					(size 1.27 1.27)
				)
			)
		)
		(property "Value" ""
			(at 0 0 0)
			(layer "F.Fab")
			(effects
				(font
					(size 1.27 1.27)
				)
			)
		)
		(duplicate_pad_numbers_are_jumpers no)
		(fp_line
			(start -0.7874 -0.4064)
			(end 0.7874 -0.4064)
			(stroke
				(width 0.1524)
				(type default)
			)
			(layer "F.SilkS")
		)
		(fp_line
			(start -0.7874 0.4064)
			(end -0.7874 -0.4064)
			(stroke
				(width 0.1524)
				(type default)
			)
			(layer "F.SilkS")
		)
		(fp_line
			(start 0.7874 -0.4064)
			(end 0.7874 0.4064)
			(stroke
				(width 0.1524)
				(type default)
			)
			(layer "F.SilkS")
		)
		(fp_line
			(start 0.7874 0.4064)
			(end -0.7874 0.4064)
			(stroke
				(width 0.1524)
				(type default)
			)
			(layer "F.SilkS")
		)
		(fp_line
			(start -0.67945 -0.305054)
			(end -0.12065 -0.305054)
			(stroke
				(width 0.1)
				(type default)
			)
			(layer "F.Fab")
		)
		(fp_line
			(start -0.67945 0.3048)
			(end -0.67945 -0.305054)
			(stroke
				(width 0.1)
				(type default)
			)
			(layer "F.Fab")
		)
		(fp_line
			(start -0.12065 -0.305054)
			(end -0.12065 -0.2794)
			(stroke
				(width 0.1)
				(type default)
			)
			(layer "F.Fab")
		)
		(fp_line
			(start -0.12065 -0.2794)
			(end 0.12065 -0.2794)
			(stroke
				(width 0.1)
				(type default)
			)
			(layer "F.Fab")
		)
		(fp_line
			(start -0.12065 0.2794)
			(end -0.12065 0.3048)
			(stroke
				(width 0.1)
				(type default)
			)
			(layer "F.Fab")
		)
		(fp_line
			(start -0.12065 0.3048)
			(end -0.67945 0.3048)
			(stroke
				(width 0.1)
				(type default)
			)
			(layer "F.Fab")
		)
		(fp_line
			(start 0.120396 0.2794)
			(end -0.12065 0.2794)
			(stroke
				(width 0.1)
				(type default)
			)
			(layer "F.Fab")
		)
		(fp_line
			(start 0.120396 0.3048)
			(end 0.120396 0.2794)
			(stroke
				(width 0.1)
				(type default)
			)
			(layer "F.Fab")
		)
		(fp_line
			(start 0.12065 -0.3048)
			(end 0.67945 -0.3048)
			(stroke
				(width 0.1)
				(type default)
			)
			(layer "F.Fab")
		)
		(fp_line
			(start 0.12065 -0.2794)
			(end 0.12065 -0.3048)
			(stroke
				(width 0.1)
				(type default)
			)
			(layer "F.Fab")
		)
		(fp_line
			(start 0.67945 -0.3048)
			(end 0.67945 0.3048)
			(stroke
				(width 0.1)
				(type default)
			)
			(layer "F.Fab")
		)
		(fp_line
			(start 0.67945 0.3048)
			(end 0.120396 0.3048)
			(stroke
				(width 0.1)
				(type default)
			)
			(layer "F.Fab")
		)
		(pad "1" smd circle
			(at -0.40005 0)
			(size 0 0)
			(layers "F.Cu" "F.Mask" "F.Paste")
			(net "P3V3_NIC1_CO_MODE")
		)
		(pad "2" smd circle
			(at 0.40005 0)
			(size 0 0)
			(layers "F.Cu" "F.Mask" "F.Paste")
			(net "GND")
		)
	)
	(footprint ""
		(layer "F.Cu")
		(at 376.34926 -293.796212 -90)
		(property "Reference" "C3542"
			(at 0 0 270)
			(layer "F.SilkS")
			(hide yes)
			(effects
				(font
					(size 1.27 1.27)
				)
			)
		)
		(property "Value" ""
			(at 0 0 270)
			(layer "F.Fab")
			(effects
				(font
					(size 1.27 1.27)
				)
			)
		)
		(duplicate_pad_numbers_are_jumpers no)
		(fp_line
			(start -0.299974 0.150114)
			(end -0.299974 -0.150114)
			(stroke
				(width 0.1)
				(type default)
			)
			(layer "F.Fab")
		)
		(fp_line
			(start 0.299974 0.150114)
			(end -0.299974 0.150114)
			(stroke
				(width 0.1)
				(type default)
			)
			(layer "F.Fab")
		)
		(fp_line
			(start -0.299974 -0.150114)
			(end 0.299974 -0.150114)
			(stroke
				(width 0.1)
				(type default)
			)
			(layer "F.Fab")
		)
		(fp_line
			(start 0.299974 -0.150114)
			(end 0.299974 0.150114)
			(stroke
				(width 0.1)
				(type default)
			)
			(layer "F.Fab")
		)
		(pad "1" smd rect
			(at -0.2667 0 270)
			(size 0.3048 0.381)
			(layers "F.Cu" "F.Mask" "F.Paste")
			(net "P1V8_PLL0_PEX3")
		)
		(pad "2" smd rect
			(at 0.2667 0 270)
			(size 0.3048 0.381)
			(layers "F.Cu" "F.Mask" "F.Paste")
			(net "GND")
		)
	)
)
